(kicad_pcb
	(version 20260206)
	(generator "pcbnew")
	(generator_version "10.0")
	(general
		(thickness 1.6)
		(legacy_teardrops no)
	)
	(paper "A4")
	(title_block
		(title "04192023_DAF0TMB3IC0_F0TG_MB_C_brd_V02_OCP.brd")
		(comment 1 "Grand Teton / footprint 2783 of 8354 (U26), pads 2782-2893 of 6102")
	)
	(layers
		(0 "F.Cu" signal "TOP")
		(4 "In1.Cu" signal "GND")
		(6 "In2.Cu" signal "IN1")
		(8 "In3.Cu" signal "GND1")
		(10 "In4.Cu" signal "IN2")
		(12 "In5.Cu" signal "GND2")
		(14 "In6.Cu" signal "IN3")
		(16 "In7.Cu" signal "GND3")
		(18 "In8.Cu" signal "VCC")
		(20 "In9.Cu" signal "VCC1")
		(22 "In10.Cu" signal "GND4")
		(24 "In11.Cu" signal "IN4")
		(26 "In12.Cu" signal "GND5")
		(28 "In13.Cu" signal "IN5")
		(30 "In14.Cu" signal "GND6")
		(32 "In15.Cu" signal "IN6")
		(34 "In16.Cu" signal "GND7")
		(2 "B.Cu" signal "BOTTOM")
		(9 "F.Adhes" user "F.Adhesive")
		(11 "B.Adhes" user "B.Adhesive")
		(13 "F.Paste" user "Package Geometry/Pastemask Top")
		(15 "B.Paste" user "Package Geometry/Pastemask Bottom")
		(5 "F.SilkS" user "Ref Des/Silkscreen Top")
		(7 "B.SilkS" user "Ref Des/Silkscreen Bottom")
		(1 "F.Mask" user "Board Geometry/Soldermask Top")
		(3 "B.Mask" user "Board Geometry/Soldermask Bottom")
		(17 "Dwgs.User" user "User.Drawings")
		(19 "Cmts.User" user "User.Comments")
		(21 "Eco1.User" user "User.Eco1")
		(23 "Eco2.User" user "User.Eco2")
		(25 "Edge.Cuts" user "Board Geometry/Outline")
		(27 "Margin" user)
		(31 "F.CrtYd" user "Package Geometry/Place Bound Top")
		(29 "B.CrtYd" user "Package Geometry/Place Bound Bottom")
		(35 "F.Fab" user "Ref Des/Assembly Top")
		(33 "B.Fab" user "Ref Des/Assembly Bottom")
	)
	(footprint ""
		(layer "F.Cu")
		(at 111.927894 -258.880356 180)
		(property "Reference" "U26"
			(at -45.05579 -61.794136 0)
			(unlocked yes)
			(layer "F.SilkS")
			(effects
				(font
					(size 0.7874 0.5842)
					(thickness 0.1524)
				)
			)
		)
		(property "Value" ""
			(at 0 0 180)
			(layer "F.Fab")
			(effects
				(font
					(size 1.27 1.27)
				)
			)
		)
		(duplicate_pad_numbers_are_jumpers no)
		(pad "C49" smd circle
			(at 10.020046 -35.189922 180)
			(size 0.450088 0.450088)
			(layers "F.Cu" "F.Mask" "F.Paste")
			(net "GND")
		)
		(pad "C50" smd circle
			(at 10.9601 -35.189922 180)
			(size 0.450088 0.450088)
			(layers "F.Cu" "F.Mask" "F.Paste")
			(net "Net_2073")
		)
		(pad "C51" smd circle
			(at 11.8999 -35.189922 180)
			(size 0.450088 0.450088)
			(layers "F.Cu" "F.Mask" "F.Paste")
			(net "Net_2072")
		)
		(pad "C52" smd circle
			(at 12.839954 -35.189922 180)
			(size 0.450088 0.450088)
			(layers "F.Cu" "F.Mask" "F.Paste")
			(net "GND")
		)
		(pad "C53" smd circle
			(at 13.780008 -35.189922 180)
			(size 0.450088 0.450088)
			(layers "F.Cu" "F.Mask" "F.Paste")
			(net "Net_2151")
		)
		(pad "C54" smd circle
			(at 14.720062 -35.189922 180)
			(size 0.450088 0.450088)
			(layers "F.Cu" "F.Mask" "F.Paste")
			(net "Net_2152")
		)
		(pad "C55" smd circle
			(at 15.660116 -35.189922 180)
			(size 0.450088 0.450088)
			(layers "F.Cu" "F.Mask" "F.Paste")
			(net "GND")
		)
		(pad "C56" smd circle
			(at 16.599916 -35.189922 180)
			(size 0.450088 0.450088)
			(layers "F.Cu" "F.Mask" "F.Paste")
			(net "GND")
		)
		(pad "C57" smd circle
			(at 17.53997 -35.189922 180)
			(size 0.450088 0.450088)
			(layers "F.Cu" "F.Mask" "F.Paste")
			(net "GND")
		)
		(pad "C58" smd circle
			(at 18.480024 -35.189922 180)
			(size 0.450088 0.450088)
			(layers "F.Cu" "F.Mask" "F.Paste")
			(net "Net_2169")
		)
		(pad "C59" smd circle
			(at 19.420078 -35.189922 180)
			(size 0.450088 0.450088)
			(layers "F.Cu" "F.Mask" "F.Paste")
			(net "Net_2173")
		)
		(pad "C60" smd circle
			(at 20.359878 -35.189922 180)
			(size 0.450088 0.450088)
			(layers "F.Cu" "F.Mask" "F.Paste")
			(net "TP_M_A_CPU1_SA_TEST40")
		)
		(pad "C61" smd circle
			(at 21.299932 -35.189922 180)
			(size 0.450088 0.450088)
			(layers "F.Cu" "F.Mask" "F.Paste")
			(net "GND")
		)
		(pad "C62" smd circle
			(at 22.239986 -35.189922 180)
			(size 0.450088 0.450088)
			(layers "F.Cu" "F.Mask" "F.Paste")
			(net "CPU1_BP1")
		)
		(pad "C63" smd circle
			(at 23.18004 -35.189922 180)
			(size 0.450088 0.450088)
			(layers "F.Cu" "F.Mask" "F.Paste")
			(net "CPU1_BP0")
		)
		(pad "C64" smd circle
			(at 24.120094 -35.189922 180)
			(size 0.450088 0.450088)
			(layers "F.Cu" "F.Mask" "F.Paste")
			(net "GND")
		)
		(pad "C65" smd circle
			(at 25.059894 -35.189922 180)
			(size 0.450088 0.450088)
			(layers "F.Cu" "F.Mask" "F.Paste")
			(net "CPU1_XTRIG_R2_L5")
		)
		(pad "C66" smd circle
			(at 25.999948 -35.189922 180)
			(size 0.450088 0.450088)
			(layers "F.Cu" "F.Mask" "F.Paste")
			(net "CPU1_XTRIG_R2_L4")
		)
		(pad "C67" smd circle
			(at 26.940002 -35.189922 180)
			(size 0.450088 0.450088)
			(layers "F.Cu" "F.Mask" "F.Paste")
			(net "GND")
		)
		(pad "C68" smd circle
			(at 27.880056 -35.189922 180)
			(size 0.450088 0.450088)
			(layers "F.Cu" "F.Mask" "F.Paste")
			(net "CPU1_SP5R2")
		)
		(pad "C69" smd circle
			(at 28.82011 -35.189922 180)
			(size 0.450088 0.450088)
			(layers "F.Cu" "F.Mask" "F.Paste")
			(net "GND")
		)
		(pad "C70" smd circle
			(at 29.75991 -35.189922 180)
			(size 0.450088 0.450088)
			(layers "F.Cu" "F.Mask" "F.Paste")
			(net "CPU1_CORETYPE0")
		)
		(pad "C71" smd circle
			(at 30.699964 -35.189922 180)
			(size 0.450088 0.450088)
			(layers "F.Cu" "F.Mask" "F.Paste")
			(net "GND")
		)
		(pad "C72" smd circle
			(at 31.640018 -35.189922 180)
			(size 0.450088 0.450088)
			(layers "F.Cu" "F.Mask" "F.Paste")
			(net "Net_2096")
		)
		(pad "C73" smd circle
			(at 32.580072 -35.189922 180)
			(size 0.450088 0.450088)
			(layers "F.Cu" "F.Mask" "F.Paste")
			(net "GND")
		)
		(pad "C74" smd circle
			(at 33.519872 -35.189922 180)
			(size 0.450088 0.450088)
			(layers "F.Cu" "F.Mask" "F.Paste")
			(net "VSENSE_PVDD18_S5_P1_DP")
		)
		(pad "C75" smd circle
			(at 34.459926 -35.189922 180)
			(size 0.450088 0.450088)
			(layers "F.Cu" "F.Mask" "F.Paste")
			(net "GND")
		)
		(pad "CA1" smd circle
			(at -34.459926 14.13002 180)
			(size 0.450088 0.450088)
			(layers "F.Cu" "F.Mask" "F.Paste")
			(net "GND")
		)
		(pad "CA2" smd circle
			(at -33.519872 14.13002 180)
			(size 0.450088 0.450088)
			(layers "F.Cu" "F.Mask" "F.Paste")
			(net "M_G_CPU1_SB_CB<2>")
		)
		(pad "CA3" smd circle
			(at -32.580072 14.13002 180)
			(size 0.450088 0.450088)
			(layers "F.Cu" "F.Mask" "F.Paste")
			(net "M_G_CPU1_SB_CB<1>")
		)
		(pad "CA4" smd circle
			(at -31.640018 14.13002 180)
			(size 0.450088 0.450088)
			(layers "F.Cu" "F.Mask" "F.Paste")
			(net "PVDD11_S3_P1")
		)
		(pad "CA5" smd circle
			(at -30.699964 14.13002 180)
			(size 0.450088 0.450088)
			(layers "F.Cu" "F.Mask" "F.Paste")
			(net "M_K_CPU1_SB_CB<2>")
		)
		(pad "CA6" smd circle
			(at -29.75991 14.13002 180)
			(size 0.450088 0.450088)
			(layers "F.Cu" "F.Mask" "F.Paste")
			(net "GND")
		)
		(pad "CA7" smd circle
			(at -28.82011 14.13002 180)
			(size 0.450088 0.450088)
			(layers "F.Cu" "F.Mask" "F.Paste")
			(net "M_K_CPU1_SB_CB<1>")
		)
		(pad "CA8" smd circle
			(at -27.880056 14.13002 180)
			(size 0.450088 0.450088)
			(layers "F.Cu" "F.Mask" "F.Paste")
			(net "GND")
		)
		(pad "CA9" smd circle
			(at -26.940002 14.13002 180)
			(size 0.450088 0.450088)
			(layers "F.Cu" "F.Mask" "F.Paste")
			(net "M_L_CPU1_SB_CB<2>")
		)
		(pad "CA10" smd circle
			(at -25.999948 14.13002 180)
			(size 0.450088 0.450088)
			(layers "F.Cu" "F.Mask" "F.Paste")
			(net "M_L_CPU1_SB_CB<1>")
		)
		(pad "CA11" smd circle
			(at -25.059894 14.13002 180)
			(size 0.450088 0.450088)
			(layers "F.Cu" "F.Mask" "F.Paste")
			(net "PVDD11_S3_P1")
		)
		(pad "CA12" smd circle
			(at -24.120094 14.13002 180)
			(size 0.450088 0.450088)
			(layers "F.Cu" "F.Mask" "F.Paste")
			(net "M_H_CPU1_SB_CB<2>")
		)
		(pad "CA13" smd circle
			(at -23.18004 14.13002 180)
			(size 0.450088 0.450088)
			(layers "F.Cu" "F.Mask" "F.Paste")
			(net "GND")
		)
		(pad "CA14" smd circle
			(at -22.239986 14.13002 180)
			(size 0.450088 0.450088)
			(layers "F.Cu" "F.Mask" "F.Paste")
			(net "M_H_CPU1_SB_CB<1>")
		)
		(pad "CA15" smd circle
			(at -21.299932 14.13002 180)
			(size 0.450088 0.450088)
			(layers "F.Cu" "F.Mask" "F.Paste")
			(net "GND")
		)
		(pad "CA16" smd circle
			(at -20.359878 14.13002 180)
			(size 0.450088 0.450088)
			(layers "F.Cu" "F.Mask" "F.Paste")
			(net "M_J_CPU1_SB_CB<2>")
		)
		(pad "CA17" smd circle
			(at -19.420078 14.13002 180)
			(size 0.450088 0.450088)
			(layers "F.Cu" "F.Mask" "F.Paste")
			(net "M_J_CPU1_SB_CB<1>")
		)
		(pad "CA18" smd circle
			(at -18.480024 14.13002 180)
			(size 0.450088 0.450088)
			(layers "F.Cu" "F.Mask" "F.Paste")
			(net "PVDD11_S3_P1")
		)
		(pad "CA19" smd circle
			(at -17.53997 14.13002 180)
			(size 0.450088 0.450088)
			(layers "F.Cu" "F.Mask" "F.Paste")
			(net "M_I_CPU1_SB_CB<2>")
		)
		(pad "CA20" smd circle
			(at -16.599916 14.13002 180)
			(size 0.450088 0.450088)
			(layers "F.Cu" "F.Mask" "F.Paste")
			(net "GND")
		)
		(pad "CA21" smd circle
			(at -15.660116 14.13002 180)
			(size 0.450088 0.450088)
			(layers "F.Cu" "F.Mask" "F.Paste")
			(net "M_I_CPU1_SB_CB<1>")
		)
		(pad "CA22" smd circle
			(at -14.720062 14.13002 180)
			(size 0.450088 0.450088)
			(layers "F.Cu" "F.Mask" "F.Paste")
			(net "GND")
		)
		(pad "CA23" smd circle
			(at -13.780008 14.13002 180)
			(size 0.450088 0.450088)
			(layers "F.Cu" "F.Mask" "F.Paste")
			(net "P5E_CPU1_P2_TX_DN<14>")
		)
		(pad "CA24" smd circle
			(at -12.839954 14.13002 180)
			(size 0.450088 0.450088)
			(layers "F.Cu" "F.Mask" "F.Paste")
			(net "P5E_CPU1_P2_TX_DP<14>")
		)
		(pad "CA25" smd circle
			(at -11.8999 14.13002 180)
			(size 0.450088 0.450088)
			(layers "F.Cu" "F.Mask" "F.Paste")
			(net "GND")
		)
		(pad "CA26" smd circle
			(at -10.9601 14.13002 180)
			(size 0.450088 0.450088)
			(layers "F.Cu" "F.Mask" "F.Paste")
			(net "P5E_CPU1_P2_TX_DN<11>")
		)
		(pad "CA27" smd circle
			(at -10.020046 14.13002 180)
			(size 0.450088 0.450088)
			(layers "F.Cu" "F.Mask" "F.Paste")
			(net "P5E_CPU1_P2_TX_DP<11>")
		)
		(pad "CA28" smd circle
			(at -9.079992 14.13002 180)
			(size 0.450088 0.450088)
			(layers "F.Cu" "F.Mask" "F.Paste")
			(net "GND")
		)
		(pad "CA29" smd circle
			(at -8.139938 14.13002 180)
			(size 0.450088 0.450088)
			(layers "F.Cu" "F.Mask" "F.Paste")
			(net "P5E_CPU1_P2_TX_DN<8>")
		)
		(pad "CA30" smd circle
			(at -7.199884 14.13002 180)
			(size 0.450088 0.450088)
			(layers "F.Cu" "F.Mask" "F.Paste")
			(net "P5E_CPU1_P2_TX_DP<8>")
		)
		(pad "CA31" smd circle
			(at -6.260084 14.13002 180)
			(size 0.450088 0.450088)
			(layers "F.Cu" "F.Mask" "F.Paste")
			(net "GND")
		)
		(pad "CA32" smd circle
			(at -5.32003 14.13002 180)
			(size 0.450088 0.450088)
			(layers "F.Cu" "F.Mask" "F.Paste")
			(net "P5E_CPU1_P2_TX_DN<5>")
		)
		(pad "CA33" smd circle
			(at -4.379976 14.13002 180)
			(size 0.450088 0.450088)
			(layers "F.Cu" "F.Mask" "F.Paste")
			(net "P5E_CPU1_P2_TX_DP<5>")
		)
		(pad "CA34" smd circle
			(at -3.439922 14.13002 180)
			(size 0.450088 0.450088)
			(layers "F.Cu" "F.Mask" "F.Paste")
			(net "GND")
		)
		(pad "CA35" smd circle
			(at -2.500122 14.13002 180)
			(size 0.450088 0.450088)
			(layers "F.Cu" "F.Mask" "F.Paste")
			(net "GND")
		)
		(pad "CA36" smd circle
			(at -1.560068 14.13002 180)
			(size 0.450088 0.450088)
			(layers "F.Cu" "F.Mask" "F.Paste")
			(net "GND")
		)
		(pad "CA40" smd circle
			(at 1.260094 14.13002 180)
			(size 0.450088 0.450088)
			(layers "F.Cu" "F.Mask" "F.Paste")
			(net "GND")
		)
		(pad "CA41" smd circle
			(at 2.199894 14.13002 180)
			(size 0.450088 0.450088)
			(layers "F.Cu" "F.Mask" "F.Paste")
			(net "GND")
		)
		(pad "CA42" smd circle
			(at 3.139948 14.13002 180)
			(size 0.450088 0.450088)
			(layers "F.Cu" "F.Mask" "F.Paste")
			(net "GND")
		)
		(pad "CA43" smd circle
			(at 4.080002 14.13002 180)
			(size 0.450088 0.450088)
			(layers "F.Cu" "F.Mask" "F.Paste")
			(net "P5E_CPU1_P0_RX_DP<10>")
		)
		(pad "CA44" smd circle
			(at 5.020056 14.13002 180)
			(size 0.450088 0.450088)
			(layers "F.Cu" "F.Mask" "F.Paste")
			(net "P5E_CPU1_P0_RX_DN<10>")
		)
		(pad "CA45" smd circle
			(at 5.96011 14.13002 180)
			(size 0.450088 0.450088)
			(layers "F.Cu" "F.Mask" "F.Paste")
			(net "GND")
		)
		(pad "CA46" smd circle
			(at 6.89991 14.13002 180)
			(size 0.450088 0.450088)
			(layers "F.Cu" "F.Mask" "F.Paste")
			(net "P5E_CPU1_P0_RX_DP<7>")
		)
		(pad "CA47" smd circle
			(at 7.839964 14.13002 180)
			(size 0.450088 0.450088)
			(layers "F.Cu" "F.Mask" "F.Paste")
			(net "P5E_CPU1_P0_RX_DN<7>")
		)
		(pad "CA48" smd circle
			(at 8.780018 14.13002 180)
			(size 0.450088 0.450088)
			(layers "F.Cu" "F.Mask" "F.Paste")
			(net "GND")
		)
		(pad "CA49" smd circle
			(at 9.720072 14.13002 180)
			(size 0.450088 0.450088)
			(layers "F.Cu" "F.Mask" "F.Paste")
			(net "P5E_CPU1_P0_RX_DP<4>")
		)
		(pad "CA50" smd circle
			(at 10.659872 14.13002 180)
			(size 0.450088 0.450088)
			(layers "F.Cu" "F.Mask" "F.Paste")
			(net "P5E_CPU1_P0_RX_DN<4>")
		)
		(pad "CA51" smd circle
			(at 11.599926 14.13002 180)
			(size 0.450088 0.450088)
			(layers "F.Cu" "F.Mask" "F.Paste")
			(net "GND")
		)
		(pad "CA52" smd circle
			(at 12.53998 14.13002 180)
			(size 0.450088 0.450088)
			(layers "F.Cu" "F.Mask" "F.Paste")
			(net "P5E_CPU1_P0_RX_DP<1>")
		)
		(pad "CA53" smd circle
			(at 13.480034 14.13002 180)
			(size 0.450088 0.450088)
			(layers "F.Cu" "F.Mask" "F.Paste")
			(net "P5E_CPU1_P0_RX_DN<1>")
		)
		(pad "CA54" smd circle
			(at 14.420088 14.13002 180)
			(size 0.450088 0.450088)
			(layers "F.Cu" "F.Mask" "F.Paste")
			(net "GND")
		)
		(pad "CA55" smd circle
			(at 15.359888 14.13002 180)
			(size 0.450088 0.450088)
			(layers "F.Cu" "F.Mask" "F.Paste")
			(net "M_C_CPU1_SB_CB<1>")
		)
		(pad "CA56" smd circle
			(at 16.299942 14.13002 180)
			(size 0.450088 0.450088)
			(layers "F.Cu" "F.Mask" "F.Paste")
			(net "GND")
		)
		(pad "CA57" smd circle
			(at 17.239996 14.13002 180)
			(size 0.450088 0.450088)
			(layers "F.Cu" "F.Mask" "F.Paste")
			(net "M_C_CPU1_SB_CB<2>")
		)
		(pad "CA58" smd circle
			(at 18.18005 14.13002 180)
			(size 0.450088 0.450088)
			(layers "F.Cu" "F.Mask" "F.Paste")
			(net "PVDDIO_P1")
		)
		(pad "CA59" smd circle
			(at 19.120104 14.13002 180)
			(size 0.450088 0.450088)
			(layers "F.Cu" "F.Mask" "F.Paste")
			(net "M_D_CPU1_SB_CB<1>")
		)
		(pad "CA60" smd circle
			(at 20.059904 14.13002 180)
			(size 0.450088 0.450088)
			(layers "F.Cu" "F.Mask" "F.Paste")
			(net "M_D_CPU1_SB_CB<2>")
		)
		(pad "CA61" smd circle
			(at 20.999958 14.13002 180)
			(size 0.450088 0.450088)
			(layers "F.Cu" "F.Mask" "F.Paste")
			(net "GND")
		)
		(pad "CA62" smd circle
			(at 21.940012 14.13002 180)
			(size 0.450088 0.450088)
			(layers "F.Cu" "F.Mask" "F.Paste")
			(net "M_B_CPU1_SB_CB<1>")
		)
		(pad "CA63" smd circle
			(at 22.880066 14.13002 180)
			(size 0.450088 0.450088)
			(layers "F.Cu" "F.Mask" "F.Paste")
			(net "GND")
		)
		(pad "CA64" smd circle
			(at 23.82012 14.13002 180)
			(size 0.450088 0.450088)
			(layers "F.Cu" "F.Mask" "F.Paste")
			(net "M_B_CPU1_SB_CB<2>")
		)
		(pad "CA65" smd circle
			(at 24.75992 14.13002 180)
			(size 0.450088 0.450088)
			(layers "F.Cu" "F.Mask" "F.Paste")
			(net "PVDDIO_P1")
		)
		(pad "CA66" smd circle
			(at 25.699974 14.13002 180)
			(size 0.450088 0.450088)
			(layers "F.Cu" "F.Mask" "F.Paste")
			(net "M_F_CPU1_SB_CB<1>")
		)
		(pad "CA67" smd circle
			(at 26.640028 14.13002 180)
			(size 0.450088 0.450088)
			(layers "F.Cu" "F.Mask" "F.Paste")
			(net "M_F_CPU1_SB_CB<2>")
		)
		(pad "CA68" smd circle
			(at 27.580082 14.13002 180)
			(size 0.450088 0.450088)
			(layers "F.Cu" "F.Mask" "F.Paste")
			(net "GND")
		)
		(pad "CA69" smd circle
			(at 28.519882 14.13002 180)
			(size 0.450088 0.450088)
			(layers "F.Cu" "F.Mask" "F.Paste")
			(net "M_E_CPU1_SB_CB<1>")
		)
		(pad "CA70" smd circle
			(at 29.459936 14.13002 180)
			(size 0.450088 0.450088)
			(layers "F.Cu" "F.Mask" "F.Paste")
			(net "GND")
		)
		(pad "CA71" smd circle
			(at 30.39999 14.13002 180)
			(size 0.450088 0.450088)
			(layers "F.Cu" "F.Mask" "F.Paste")
			(net "M_E_CPU1_SB_CB<2>")
		)
		(pad "CA72" smd circle
			(at 31.340044 14.13002 180)
			(size 0.450088 0.450088)
			(layers "F.Cu" "F.Mask" "F.Paste")
			(net "PVDDIO_P1")
		)
		(pad "CA73" smd circle
			(at 32.280098 14.13002 180)
			(size 0.450088 0.450088)
			(layers "F.Cu" "F.Mask" "F.Paste")
			(net "M_A_CPU1_SB_CB<1>")
		)
		(pad "CA74" smd circle
			(at 33.219898 14.13002 180)
			(size 0.450088 0.450088)
			(layers "F.Cu" "F.Mask" "F.Paste")
			(net "M_A_CPU1_SB_CB<2>")
		)
		(pad "CA75" smd circle
			(at 34.159952 14.13002 180)
			(size 0.450088 0.450088)
			(layers "F.Cu" "F.Mask" "F.Paste")
			(net "GND")
		)
		(pad "CB2" smd circle
			(at -33.990026 14.940026 180)
			(size 0.450088 0.450088)
			(layers "F.Cu" "F.Mask" "F.Paste")
			(net "M_G_CPU1_SB_DQ<0>")
		)
		(pad "CB3" smd circle
			(at -33.049972 14.940026 180)
			(size 0.450088 0.450088)
			(layers "F.Cu" "F.Mask" "F.Paste")
			(net "GND")
		)
		(pad "CB4" smd circle
			(at -32.109918 14.940026 180)
			(size 0.450088 0.450088)
			(layers "F.Cu" "F.Mask" "F.Paste")
			(net "M_G_CPU1_SB_CB<3>")
		)
		(pad "CB5" smd circle
			(at -31.170118 14.940026 180)
			(size 0.450088 0.450088)
			(layers "F.Cu" "F.Mask" "F.Paste")
			(net "GND")
		)
		(pad "CB6" smd circle
			(at -30.230064 14.940026 180)
			(size 0.450088 0.450088)
			(layers "F.Cu" "F.Mask" "F.Paste")
			(net "M_K_CPU1_SB_DQ<0>")
		)
		(pad "CB7" smd circle
			(at -29.29001 14.940026 180)
			(size 0.450088 0.450088)
			(layers "F.Cu" "F.Mask" "F.Paste")
			(net "M_K_CPU1_SB_CB<3>")
		)
		(pad "CB8" smd circle
			(at -28.349956 14.940026 180)
			(size 0.450088 0.450088)
			(layers "F.Cu" "F.Mask" "F.Paste")
			(net "GND")
		)
		(pad "CB9" smd circle
			(at -27.409902 14.940026 180)
			(size 0.450088 0.450088)
			(layers "F.Cu" "F.Mask" "F.Paste")
			(net "M_L_CPU1_SB_DQ<0>")
		)
		(pad "CB10" smd circle
			(at -26.470102 14.940026 180)
			(size 0.450088 0.450088)
			(layers "F.Cu" "F.Mask" "F.Paste")
			(net "GND")
		)
		(pad "CB11" smd circle
			(at -25.530048 14.940026 180)
			(size 0.450088 0.450088)
			(layers "F.Cu" "F.Mask" "F.Paste")
			(net "M_L_CPU1_SB_CB<3>")
		)
		(pad "CB12" smd circle
			(at -24.589994 14.940026 180)
			(size 0.450088 0.450088)
			(layers "F.Cu" "F.Mask" "F.Paste")
			(net "GND")
		)
		(pad "CB13" smd circle
			(at -23.64994 14.940026 180)
			(size 0.450088 0.450088)
			(layers "F.Cu" "F.Mask" "F.Paste")
			(net "M_H_CPU1_SB_DQ<0>")
		)
		(pad "CB14" smd circle
			(at -22.709886 14.940026 180)
			(size 0.450088 0.450088)
			(layers "F.Cu" "F.Mask" "F.Paste")
			(net "M_H_CPU1_SB_CB<3>")
		)
	)
)
